Release date : 20230626
Version : 00020002 (Formal Release)
JED File : F0TG_MB_CPLD_v00020002_20230626_signed.jed
Author : <name>
- Update Method
   - fw-util mb --update mb_cpld F0TG_MB_CPLD_v00020002_20230626_signed.jed

- Important Note
   - N/A

- Whats New
   - Modify RESETL signal to separate GPU side and Retimer side.

- Bug Fixes
   - Change back GPU_PWR_ON condition from iFM_SLPS3_N to CPU RESETL.
   - Remove SCM present pin & MEM power good pin workaround.

- Module(s) Affected
   - T6G_MB.lpf
   - pwr_seq.v
   - top.v
   - gpu_pwrseq_fsm.v

*************************************************************************************************************************************************************************

Release date : 20230529
Version : 00020001 (Formal Release)
JED File : F0TG_MB_CPLD_v00020001_20230529_signed.jed
Author : <name>
- Update Method
   - fw-util mb --update mb_cpld F0TG_MB_CPLD_v00020001_20230529_signed.jed

- Important Note
   - N/A

- Whats New
   - Add PMIC_PCAMP.v for fatal error inject testing on DDR5 DIMM.
   - Add PMIC_ERROR signal to cut off normal power when DDR5 occurred fatal.
   - Add r2_IRQ_SML1_PMBUS_ALERT_N signal to control system Throttle function.
   - Add PWR_FAULT_ALERT signal on SGPIO out bit 85 for BMC quick dump function when system power failure.
   - Create SGPIO out function to SCM CPLD that have main function for reset BMC by external reset from MB CPLD.   
   - Add FM_CPU0_PWR_BTN_N debounce.
   - Add wOVERT_BMC_DUMP_CPLT signal on SGPIO input bit 16 for BMC quick dump log when GPU OVERT.
   - Add FM_CLR_CMOS signal on SGPIO input bit 27 for BMC clear CMOS function.
   - Add r2_FM_BIOS_POST_CMPLT_BUF_R_N signal mark on FM_APML_MUX2_OE_R_N and FM_SEC_MUX_OE_R_N to prevent BMC error trigger.

- Bug Fixes
   - Change BMC PCIE reset timing from RST_CPU0_PERST0_R_N to FM_HDT_HDR_RESET_N to fixed BIOS early reading TPM feature.
   - Update gpu_pwrseq_fsm.v and swb_pwrseq_fsm.v that followed GTT design.
   - Change back SGPIO out Bit 115 to wRST_PERST_CPU0_SWB_N&wRST_PERST_CPU1_SWB_N for locked SDK reading retimer from BMC.

- Module(s) Affected
   - T6G_MB.ldf
   - T6G_MB.lpf
   - control.v
   - PMIC_PCAMP.v
   - pwr_seq.v
   - top.v
   - gpu_pwrseq_fsm.v
   - swb_pwrseq_fsm.v
   - Archer_City_Main_wrapper_F0TG.sv
   - Archer_City_Main_F0TG.v

*************************************************************************************************************************************************************************

Release date : 20230508
Version : 00020000 (Formal Release)
JED File : F0TG_MB_CPLD_v00020000_20230508_signed.jed
Author : <name>
- Update Method
   - fw-util mb --update mb_cpld F0TG_MB_CPLD_v00020000_20230508_signed.jed

- Important Note
   - N/A

- Whats New
   - Change SGPIO bit115 signal from wRST_PERST_CPU0_SWB_N&wRST_PERST_CPU1_SWB_N to rCPU_RESET_L_DLY_8S that can be provided early traning timing of Retimer init & sensord by BMC. 
   - Add debounce on SGPIO bit2,bit8,bit20,bit21,bit32,bit51 and bit53 input signals from BMC to prevent SGPIO error toggle on CPU side.

- Bug Fixes
   - Separate reset timing of Retimer core reset to prevent over power ripple when Retimer FW loading.

- Module(s) Affected
   - top.v
   - T6G_MB.lpf

*************************************************************************************************************************************************************************

Release date : 20230420
Version : 00010006 (Formal Release)
JED File : F0TG_MB_CPLD_v00010006_20230420_signed.jed
Author : <name>
- Update Method
   - fw-util mb --update mb_cpld F0TG_MB_CPLD_v00010006_20230420_signed.jed

- Important Note
   - N/A

- Whats New
   - Add debounce on FM_CPU0_SYS_RESET_N signal to prevent error trigger from BMC SGPIO input.(top.v)

- Bug Fixes
   - Remove workaround PWGD_P3V3_OCP_V3_1
   - Remove workaround PWGD_P3V3_OCP_V3_1
   - Remove workaround PWGD_P3V3_E1S_1
   - Remove workaround PRSNT_SWB_ISO_R_N

- Module(s) Affected
   - top.v
   - T6G_MB.lpf

*************************************************************************************************************************************************************************

Release date : 20230321
Version : 00010005 (Formal Release)
JED File : F0TG_MB_CPLD_v00010005_20230321.jed
Author : <name>
- Important Note
   - N/A

- Whats New
   - Add FM_PCH_BMC_RST_N signal to control BMC reset timing that follow F0TMB_00020000.(Archer_City_Main_F0TG.v)
   - Add RESETL and FM_BIOS_POST_CMPLT_BMC_N signal to control BMC reset timing that follow F0TMB_00020000.(Archer_City_Main_F0TG.v,top.v)
   - Add oBMCPostCode state log from Archer_City_Main_F0TG.v to top.v for I2C debug register mapping.(top.v)
   - Update full ac_bmc_pwrseq_fsm.v verilog file that follow GTT F0TMB_00020000 setting.(ac_bmc_pwrseq_fsm.v)
   - Add one more SGPIO bus SGPIO0_SCM_CPLD_DI/DO to connect SCM CPLD to prevent BMC leakage and BMC self-reset.(top.v)

- Bug Fixes
   - Rename FM_BMC_READY_PDB_N to FM_PDB_BUF_EN_N and add SCM CPLD SGPIO bus to prevent BMC leakage.(top.v)
   - Change iBMC_PWR_EN from 1'b1 to PWRGD_P1V8_PCH_AUX_FF to prevent BMC leakage.(top.v)

- Module(s) Affected
   - top.v
   - T6G_MB.lpf
   - ac_bmc_pwrseq_fsm.v
   - Archer_City_Main_F0TG.v
   - Archer_City_Main_wrapper_F0TG.v

*************************************************************************************************************************************************************************

Release date : 20230223
Version : 00010004 (Formal Release)
JED File : F0TG_MB_CPLD_v00010004_20230223.jed
Author : <name>
- Important Note
   - N/A

- Whats New
   - Add RST_PERST_CPUx_SWB_N signal on SGPIO output bit 115 that can be checked Retimer FW ready from BMC.
   - Add RST_SMB_RT_R2_N_SEL signal on SGPIO input bit 15 that can be controlled Retimer I2C MUX reset signal by BMC.
   - Delay P1V8_RETIMER_CPUx_R_EN power on timing from PWRGD_P12V_STBY_R state to FM_CPU0_SLP_S3_N state.

- Bug Fixes
   - Remove VR OCP_L and PMALERT signals from protection mechanism of PROCHOT.
   - Postponed FM_RST_CPU01_RESETL_N from GPU_HSC_EN_ON state to HGX_DETECT_ON state from GPU power on state machine to fixed GPU loss STBY power when DC off stage.
   - Change MAIN_PWR_DOWN next state from STBY_PWR_DOWN to INIT that can prevent GPU STBY Power droped when DC off stage.
   - Set FM_PLD_CLKS_DEV_EN_GPU to 1'b1 to resolve SWB & GPU power on state machine cant enter final state issue.
   - Remove UV_ALERT_N & FM_UV_ADR_TRIGGER_R_N workaround because the solution of schematic already implemneted on latest DVT 8 retimer MB.
   - Fixed CPU_RESET_L edge trigger mechanism that problem will cause SWB cant release PCIE reset.
   - Delay reset control timing of Retimer I2C MUX that can fix Retimer FW loading failed issue.
   - Delay select control timing of Retimer EEPROM MUX that can fix Retimer FW loading failed issue.

- Module(s) Affected
   - top.v
   - T6G_MB.lpf
   - gpu_pwrseq_fsm.v
   - Archer_City_Main_F0TG.v
   - PWR_THROT.v

*************************************************************************************************************************************************************************

Release date : 20230204
Version : 00010003 (Formal Release)
JED File : F0TG_MB_CPLD_v00010003_20230204.jed
Author : <name>
- Important Note
   - N/A

- Whats New
   - Add rCPU_RESET_L to control GPU power sequence.(top.v)
   - rCPU_RESET_L will assert high when AC power on only once FM_RST_CPU0_RESETL_N low to high.(top.v)
   - Add retimer control signals on I2C Register Map.(top.v)

- Bug Fixes
   - Change SGPIO output bit9,11,58,60 to BMC value by BMC Roy's requirement.This is CPLD healthy function(top.v)
   - Reverse SGPIO input bit22 GPU_WP_HW_CTRL_R_N that follow F0T initial setting default setting to 1'b0.The signal will cause GPU can't update FW(top.v)
   - Modify Retimer RESET_N's contorl signal RESET_L that have to delay 100ms(rCPU_RESET_L_DLY_100MS) to prevent PCIE devices loss.(top.v)
   - Fix workaround FM_BMC_READY on Archer_City_Main_wrapper_F0TG.v input signal.(top.v)
   - Change iFM_RST_CPU01_RESETL_N input signal from FM_HDT_HDR_RESET_N to rCPU_RESET_L_DLY_100MS on Archer_City_Main_wrapper_F0TG.v that can be prevented PCIE device loss.(top.v)

- Module(s) Affected
   - top.v
   - T6G_MB.lpf
   - gpu_pwrseq_fsm.v

*************************************************************************************************************************************************************************

Release date : 20230107
Version : 00010002 (Formal Release)
JED File : F0TG_MB_CPLD_v0102_20230107.jed
Author : <name>
- Important Note
   - N/A

- Whats New
   - Remove wFM_GPU_PWRGD_ISO_R signal checking from power sequence that follow NV's spec and need to use SWB CPLD 00020000 together.
   - Modify gpu_pwrseq_fsm.v and swb_pwrseq_fsm.v to follow F0T 08010004
   - Add FM_GPU_PWR_EN signal control on SWB to let SWB power on after than GPU Delta-Next

- Bug Fixes
   - Change back CPU1 PERST delay time from 1 sec to no delay to prevent CPU1 PCIE device all loss.
   - Add back FM_RST_CPU01_RESETL_N signal to fix retimer sequence issue of M1 debug board.

- Module(s) Affected
   - top.v
   - pwr_seq.v
   - T6G_MB.lpf
   - gpu_pwrseq_fsm.v
   - swb_pwrseq_fsm.v
   - Archer_City_Main_F0TG.v
   - Archer_City_Main_wrapper_F0TG.sv

*************************************************************************************************************************************************************************

Release date : 20221226
Version : 00010001 (Formal Release)
JED File : F0TG_MB_v0100_20221226.jed
Author : <name>
- Important Note
   - N/A

- Whats New
   - Add rMASK_EVENT signal to separate Board version to config function pin for each stage.

- Bug Fixes
   - Use rMASK_EVENT signal to control CPU1 PERST delay 1S(DVT) or not(EVT) for SWB CPLD issue.

- Module(s) Affected
   - top.v
   - T6G_MB.lpf

*************************************************************************************************************************************************************************

Release date : 20221222
Version : 00010000 (Formal Release)
JED File : F0TG_MB_v0100_20221222.jed
Author : <name>
- Important Note
   - N/A

- Whats New
   - Add more GPIO to control 8 retimer or 2 retimer.(top.v / T6G_MB.lpg)
   - OCP power sequence control change to HW schematic control(top.v)
   - OCP/E1S ALERT change from P3V3 only to P3V3 and P12V(top.v)

- Bug Fixes
   - delay CPU1 PERST 1s to resolve CPU1 PCIE device loss after add Retimer with cascade RC FW. BTW SWB CPLD need to change PEX SYS_RST PERST signals from CPU0&CPU1 to CPU0|CPU1 to prevent loss all PCIE devices of CPU0.
   - FM_CPU0_PWR_BTN_N & FM_CPU0_SYS_RESET_N change control source from BMC_READY to SGPIO_READY by BMC Peter's requirement to resolve BMC 50.1 issue.
   - change FM_BMC_READY function from active high to active low by BMC Peter's requirement to resolve BMC 50.1 issue.

- Module(s) Affected
   - top.v
   - T6G_MB.lpf

*************************************************************************************************************************************************************************

Release date : 20221118
Version : 00000009 (Formal Release)
JED File : F0TG_MB_CPLD_v0009_20221118.jed
Author : <name>
- Important Note
   - N/A

- Whats New
   - Add SGPIO.bit9,bit11,bit58,bit60 output to SCM that can help DCSCM to confirm CPLD SGPIO signals are ready.(top.v)
   - Add SWB and GPU sequence root state on register 0x09 of SCM I2C MM8.(top.v)

- Bug Fixes
   - Add FM_PWRGD_PVDD18_S5_P1 signal to control FM_PLD_CPU1_PRSNT_HDT to prevent PVDD18_S5_P1 leakage.(top.v / control.v)
   - Add FM_BMC_READY to control FM_CPU0_SYS_RESET_N to prevent system failure reboot when BMC slef-reset.(top.v)
   - Fixed FM_LED_PWRGD_PVDD18_S5_P1 wrong coding.(top.v)

- Module(s) Affected
   - top.v
   - control.v
   - T6G_MB.lpf
   - gpu_pwrseq_fsm.v
   - swb_pwrseq_fsm.v
   - Archer_City_Main_F0TG.v
   - Archer_City_Main_wrapper_F0TG.sv

*************************************************************************************************************************************************************************

Release date : 20221014
Version : 00000008 (Formal Release)
JED File : F0TG_MB_CPLD_v0008_20221014.jed
Author : <name>
- Important Note
   - N/A

- Whats New
   - Postpone CPU PWR_BTN_L signal(FM_CPU0_PWR_BTN_N) when BMC is ready.(top.v / control.v)
   - Add PRSNT_N_E1S_1_R workaround to fix 2nd source Hynix can not detected issue.(top.v)
   - Modify MB Power good signal to let BMC checking power off ready by SLP_S3 and checking power on ready by PWROK.(top.v)
   - Modify BMC Debug I2c register 0x20,0x21,0x24,0x27~0x29,0x2c,0x2f.(top.v)

- Bug Fixes
   - MB have one more power on -> power off state when AC power on.
   - BIOS update fw fail when BMC waiting power signal timeout.

- Module(s) Affected
   - top.v
   - control.v
   - T6G_MB.lpf
   - gpu_pwrseq_fsm.v

*************************************************************************************************************************************************************************

Release date : 20220929
Version : 00000007 (Formal Release)-Final
JED File : F0TG_MB_CPLD_v0007_20220929.jed
Author : <name>
- Important Note
   - N/A

- Whats New
   - Add GPU_FPGA_EROT_RST_R_N and GPU_FPGA_EROT_RECOV_R_N pin assignment to help HWV measurement.(top.v)
   - Modify BMC I2C coding that re-coding from regc_new.v to SMBusControl.v address keep 0x23.(top.v)
   - Modify SGPIO_MB.v to add oPData_reg for watching SGPIO status currently by I2C.(top.v & SGPIO_MB.v)
   - Add IRQ_SMI_ACTIVE_N_R on SGPIO input for SIT SEL log recording.(top.v)
   - Remove iFM_RST_CPU01_RESETL_N signal on FM_GPU_PWR_EN control that is TestBoard retimer workaround only.(gpu_pwrseq_fsm.v)
   - Modify sol_uart_ch_sel control signal to add filter on FM_SOL_UART_CH_SEL_FF that follow F0TMB_00000110.(Archer_City_Main_F0TG.v)
   - Modify oSMB_BMC_SWB_EN control signal from ~iFM_BIC_READY_N to iSWB_HSC_PWRGD_ISO_R_FF that follow F0TMB_00000110.(Archer_City_Main_F0TG.v)
   - Modify wCPU_MEM_PWR_FLT control signal to unmark wCpuMemFlt that follow F0TMB_00000110. (Archer_City_Main_F0TG.v)
   - Update DBC_control.v that follow F0TMB_00000110.(DBC_control.v)
   - Add SMBusControl.v and SMBusRegs.v to replace I2C coding on regc_new.v (SMBusControl.v & SMBusRegs.v)
   - Add workaround to resolve GPU power sequence will enter power fault status.(gpu_pwrseq_fsm.v)

- Bug Fixes
   - Correct r2_PWRGD_V3_1_PWR_GOOD and r2_PWRGD_V3_2_PWR_GOOD default setting from 1'b1 to 1'b0.(top.v)
   - Fixed CPLD I2C low voltage issue that change SMB_2_PLD_3V3AUX_SCL_R2 and SMB_CPU_5_R1_SCL from Pull-down to None. (T6G_MB.lpf)
   - Fixed PCIE loss issue on Delta Next GPU that Step1 is to add wFM_GPU_PWRGD_ISO_R and GPU_PRSNT_N_ISO_R in MB Power sequence to control PCIE clock output timing after than GPU Base Power Good signal.(pwr_seq.v)
   - Fixed PCIE loss issue on Delta Next GPU that Step2 is to add CPU_PWR_PG_DLY_DONE_CHECK signal on GPU sequence to make sure PCIE clock output late than GPU_BASE_STBY_EN timing.(gpu_pwrseq_fsm.v)
   - Fixed F0TG cant power when only CPU0 issue that modify P12V_RUN_PWR_SEQ_DONE to add P0_STBY_PWR_SEQ_DONE and FM_PRSNT_CPU1_R_N control signals.(pwr_seq.v)

- Module(s) Affected
   - top.v
   - Archer_City_Main_wrapper_F0TG.sv
   - Archer_City_Main_F0TG
   - DBC_control.v
   - SGPIO_MB.v
   - T6G_MB.lpf
   - pwr_seq.v0
   - gpu_pwrseq_fsm.v

*************************************************************************************************************************************************************************

Release date : 20220908
Version : 00000006 (Formal Release)
JED File : F0TG_MB_impl1_v0006_20220908.jed
Author : <name>
- Important Note
   - N/A

- Whats New
   - FM_CPU0_FPGA_SPARE_2 change to Input and connect to SCM_IRQ_1V8_R_N output pin that follow F0T design.
   - FM_CPU1_FPGA_SPARE3 unused , so change to output pin and set default 1'bz.
   - FPGA_IO3V3_RSVD_1 unused , so it is unblocked and set default 1'bz.
   - FM_CPU1_FPGA_SPARE1(FM_BMC_READY_R_N) set default to 1'b1.
   - Output P0_PWR_ERR/P1_PWR_ERR to SGPIO.bit87/88 from pwr_seq.v for BMC Power event log.
   - Change CPU_THERMTRIP_R_N setting that CPU1_THERMTRIP_R_N to r2_CPU1_THERMTRIP_R_N.
   - FM_CPU0_SYS_RESET_N Need to change SCM_SYS_PWROK to S0 All power ok(CPU_physical_pg) because SCM_SYS_PWROK will pull low when FM_CPU0_SYS_RESET_N be asserted

- Bug Fixes
   - Fixed BMC can't use reset command and reset button to reset MB system.

- Module(s) Affected
   - top.v
   - pwr_seq.v
   - T6G_MB.lpf

*************************************************************************************************************************************************************************

Release date : 20220802
Version : 00000005_pre1
JED File : N/A
Author : <name>
- Important Note
   - N/A

- Whats New
   - Update SGPIO1 input 0~68 and wait to modify input 69~127 and output.
   - Follow F0T add RST_BMC_FROM_SWB_ISO_R_N signal.
   - Add FM_RST_CPU01_RESETL_N signal to delay FM_GPU_PWR_EN power on timing to meet PCIE sequence on Debug
   - Add r2_UV_ALERT_N workaround to resolve LT6700 issue
   - correct coding from ~sgpio1_reg_out[11] to sgpio1_reg_out[11]
   - Remove SGPIO54~SGPIO56 setting after check with BIOS
   - Workaround to close CRASHDUMP and USB_OC function from SGPIO to avoid system hang.
   - CLK_GEN2_BMC_RC_OE_R_N set default to 1'b1 to fix PCIE can't train to GEN2 (5G) issue..
   - CLK_GEN2_GPU_FPGA_OE_R_N to fix coding mistake that change from 1'bz to 1'b1

- Bug Fixes
   - N/A

- Module(s) Affected
   - top.v
   - Archer_City_Main_wrapper_F0TG.sv
   - Archer_City_Main_F0TG
   - T6G_MB.lpf
   - pwr_seq.v0
   - gpu_pwrseq_fsm.v
   - control.v